# BASEBOARD_FAB2 (Tioga Pass) — schematic netlist excerpt (pin names and nets, part order shuffled) for the footprints in the layout excerpt that follows; sources: Cadence DE-HDL packaged netlist, KiCad conversion of Wiwynn_Tioga_Pass_MB.brd

R1B12  RES  16K 1.0% CHIP  pkg 0402  page 226 : A = VR_PVDDQ_KLM_XADDR1 ; B = GND
L1C1  IND-300NH-20-GP  pkg DISCRET-GB1  page 210 : S = VR_PVSA_CPU1_PHASE_SW ; F = PVSA_CPU1

Q9A2  FET_N_DUAL  NTJD4001N FET  pkg SMLF  page 119
  SOURCE(0)  = GND
  GATE(0)  = FM_PWR_LED_N
  DRAIN(0)  = FM_PWR_LED_K
  SOURCE(0)  = GND
  GATE(0)  = FM_PWR_LED
  DRAIN(0)  = FM_PWR_LED

(kicad_pcb
	(version 20260206)
	(generator "pcbnew")
	(generator_version "10.0")
	(general
		(thickness 1.6)
		(legacy_teardrops no)
	)
	(paper "A4")
	(title_block
		(title "Wiwynn_Tioga_Pass_MB.brd")
		(comment 1 "Tioga Pass / footprints 535-537 of 4770")
	)
	(layers
		(0 "F.Cu" signal "TOP")
		(4 "In1.Cu" signal "L2GND")
		(6 "In2.Cu" signal "L3")
		(8 "In3.Cu" signal "L4GND")
		(10 "In4.Cu" signal "L5")
		(12 "In5.Cu" signal "L6GND")
		(14 "In6.Cu" signal "L7VCC")
		(16 "In7.Cu" signal "L8VCC")
		(18 "In8.Cu" signal "L9GND")
		(20 "In9.Cu" signal "L10")
		(22 "In10.Cu" signal "L11GND")
		(24 "In11.Cu" signal "L12")
		(26 "In12.Cu" signal "L13GND")
		(2 "B.Cu" signal "BOTTOM")
		(9 "F.Adhes" user "F.Adhesive")
		(11 "B.Adhes" user "B.Adhesive")
		(13 "F.Paste" user "Package Geometry/Pastemask Top")
		(15 "B.Paste" user "Package Geometry/Pastemask Bottom")
		(5 "F.SilkS" user "Ref Des/Silkscreen Top")
		(7 "B.SilkS" user "Ref Des/Silkscreen Bottom")
		(1 "F.Mask" user "Board Geometry/Soldermask Top")
		(3 "B.Mask" user "Board Geometry/Soldermask Bottom")
		(17 "Dwgs.User" user "User.Drawings")
		(19 "Cmts.User" user "User.Comments")
		(21 "Eco1.User" user "User.Eco1")
		(23 "Eco2.User" user "User.Eco2")
		(25 "Edge.Cuts" user "Board Geometry/Outline")
		(27 "Margin" user)
		(31 "F.CrtYd" user "Package Geometry/Place Bound Top")
		(29 "B.CrtYd" user "Package Geometry/Place Bound Bottom")
		(35 "F.Fab" user "Ref Des/Assembly Top")
		(33 "B.Fab" user "Ref Des/Assembly Bottom")
	)
	(footprint ""
		(layer "F.Cu")
		(at 6.35 -127.127 90)
		(property "Reference" "R1B12"
			(at -0.8382 -0.67818 90)
			(unlocked yes)
			(layer "F.SilkS")
			(effects
				(font
					(size 0.4064 0.254)
					(thickness 0.1524)
				)
				(justify left)
			)
		)
		(property "Value" ""
			(at 0 0 90)
			(layer "F.Fab")
			(effects
				(font
					(size 1.27 1.27)
				)
			)
		)
		(duplicate_pad_numbers_are_jumpers no)
		(fp_poly
			(pts
				(xy -0.2794 -0.1016) (xy 0.2794 -0.1016) (xy 0.2794 0.9906) (xy -0.2794 0.9906)
			)
			(stroke
				(width 0)
				(type default)
			)
			(fill no)
			(layer "F.CrtYd")
		)
		(fp_line
			(start 0.2794 -0.1016)
			(end -0.2794 -0.1016)
			(stroke
				(width 0.1)
				(type default)
			)
			(layer "F.Fab")
		)
		(fp_line
			(start -0.2794 -0.1016)
			(end -0.2794 0.9906)
			(stroke
				(width 0.1)
				(type default)
			)
			(layer "F.Fab")
		)
		(fp_line
			(start 0.2794 0.9906)
			(end 0.2794 -0.1016)
			(stroke
				(width 0.1)
				(type default)
			)
			(layer "F.Fab")
		)
		(fp_line
			(start -0.2794 0.9906)
			(end 0.2794 0.9906)
			(stroke
				(width 0.1)
				(type default)
			)
			(layer "F.Fab")
		)
		(pad "1" smd rect
			(at 0 0 90)
			(size 0.508 0.508)
			(layers "F.Cu" "F.Mask" "F.Paste")
			(net "VR_PVDDQ_KLM_XADDR1")
		)
		(pad "2" smd rect
			(at 0 0.889 90)
			(size 0.508 0.508)
			(layers "F.Cu" "F.Mask" "F.Paste")
			(net "GND")
		)
		(zone
			(layer "F.Cu")
			(hatch none 0.5)
			(connect_pads
				(clearance 0)
			)
			(min_thickness 0.25)
			(keepout
				(tracks allowed)
				(vias not_allowed)
				(pads allowed)
				(copperpour not_allowed)
				(footprints allowed)
			)
			(placement
				(enabled no)
				(sheetname "")
			)
			(fill
				(thermal_gap 0.5)
				(thermal_bridge_width 0.5)
				(island_removal_mode 0)
			)
			(polygon
				(pts
					(xy 6.604 -126.873) (xy 6.604 -127.381) (xy 6.985 -127.381) (xy 6.985 -126.873)
				)
			)
		)
		(zone
			(layer "F.Cu")
			(hatch none 0.5)
			(connect_pads
				(clearance 0)
			)
			(min_thickness 0.25)
			(keepout
				(tracks not_allowed)
				(vias allowed)
				(pads allowed)
				(copperpour not_allowed)
				(footprints allowed)
			)
			(placement
				(enabled no)
				(sheetname "")
			)
			(fill
				(thermal_gap 0.5)
				(thermal_bridge_width 0.5)
				(island_removal_mode 0)
			)
			(polygon
				(pts
					(xy 6.985 -126.873) (xy 6.985 -127.381) (xy 6.604 -127.381) (xy 6.604 -126.873)
				)
			)
		)
	)
	(footprint ""
		(layer "F.Cu")
		(at 40.036496 -97.671382)
		(property "Reference" "L1C1"
			(at 3.378708 -4.251706 0)
			(unlocked yes)
			(layer "F.SilkS")
			(effects
				(font
					(size 0.4064 0.254)
					(thickness 0.1524)
				)
			)
		)
		(property "Value" ""
			(at 0 0 0)
			(layer "F.Fab")
			(effects
				(font
					(size 1.27 1.27)
				)
			)
		)
		(duplicate_pad_numbers_are_jumpers no)
		(fp_line
			(start -1.1303 -3.199892)
			(end 8.3693 -3.199892)
			(stroke
				(width 0.1524)
				(type default)
			)
			(layer "F.SilkS")
		)
		(fp_line
			(start -1.1303 -1.6637)
			(end -1.1303 -3.199892)
			(stroke
				(width 0.1524)
				(type default)
			)
			(layer "F.SilkS")
		)
		(fp_line
			(start -1.1303 3.199892)
			(end -1.1303 1.6637)
			(stroke
				(width 0.1524)
				(type default)
			)
			(layer "F.SilkS")
		)
		(fp_line
			(start 8.3693 -3.199892)
			(end 8.3693 -1.6637)
			(stroke
				(width 0.1524)
				(type default)
			)
			(layer "F.SilkS")
		)
		(fp_line
			(start 8.3693 1.6637)
			(end 8.3693 3.199892)
			(stroke
				(width 0.1524)
				(type default)
			)
			(layer "F.SilkS")
		)
		(fp_line
			(start 8.3693 3.199892)
			(end -1.1303 3.199892)
			(stroke
				(width 0.1524)
				(type default)
			)
			(layer "F.SilkS")
		)
		(fp_rect
			(start -1.1303 3.199892)
			(end 8.3693 -3.199892)
			(stroke
				(width 0)
				(type default)
			)
			(fill no)
			(layer "F.CrtYd")
		)
		(fp_line
			(start -1.1303 -3.199892)
			(end 8.3693 -3.199892)
			(stroke
				(width 0.1)
				(type default)
			)
			(layer "F.Fab")
		)
		(fp_line
			(start -1.1303 3.199892)
			(end -1.1303 -3.199892)
			(stroke
				(width 0.1)
				(type default)
			)
			(layer "F.Fab")
		)
		(fp_line
			(start 8.3693 -3.199892)
			(end 8.3693 3.199892)
			(stroke
				(width 0.1)
				(type default)
			)
			(layer "F.Fab")
		)
		(fp_line
			(start 8.3693 3.199892)
			(end -1.1303 3.199892)
			(stroke
				(width 0.1)
				(type default)
			)
			(layer "F.Fab")
		)
		(pad "1" smd rect
			(at 0 0)
			(size 3.683 2.667)
			(layers "F.Cu" "F.Mask" "F.Paste")
			(net "VR_PVSA_CPU1_PHASE_SW")
		)
		(pad "2" smd rect
			(at 7.239 0)
			(size 3.683 2.667)
			(layers "F.Cu" "F.Mask" "F.Paste")
			(net "PVSA_CPU1")
		)
	)
	(footprint ""
		(layer "F.Cu")
		(at 475.2213 -138.557 90)
		(property "Reference" "Q9A2"
			(at 2.83591 -1.4351 0)
			(unlocked yes)
			(layer "F.SilkS")
			(effects
				(font
					(size 0.7874 0.5842)
					(thickness 0.1524)
				)
				(justify left)
			)
		)
		(property "Value" ""
			(at 0 0 90)
			(layer "F.Fab")
			(effects
				(font
					(size 1.27 1.27)
				)
			)
		)
		(duplicate_pad_numbers_are_jumpers no)
		(fp_circle
			(center -0.508 -0.7874)
			(end -0.508 -0.6604)
			(stroke
				(width 0.254)
				(type default)
			)
			(fill no)
			(layer "F.SilkS")
		)
		(fp_poly
			(pts
				(xy 0.2159 1.7526) (xy 1.5621 1.7526) (xy 1.5621 -0.4572) (xy 0.2159 -0.4572)
			)
			(stroke
				(width 0)
				(type default)
			)
			(fill no)
			(layer "F.CrtYd")
		)
		(fp_line
			(start 1.5621 -0.45466)
			(end 0.2159 -0.45466)
			(stroke
				(width 0.1)
				(type default)
			)
			(layer "F.Fab")
		)
		(fp_line
			(start 0.2159 -0.45466)
			(end 0.2159 1.75514)
			(stroke
				(width 0.1)
				(type default)
			)
			(layer "F.Fab")
		)
		(fp_line
			(start 1.5621 1.75514)
			(end 1.5621 -0.45466)
			(stroke
				(width 0.1)
				(type default)
			)
			(layer "F.Fab")
		)
		(fp_line
			(start 0.2159 1.75514)
			(end 1.5621 1.75514)
			(stroke
				(width 0.1)
				(type default)
			)
			(layer "F.Fab")
		)
		(fp_circle
			(center -0.508 -0.7874)
			(end -0.508 -0.6604)
			(stroke
				(width 0.254)
				(type default)
			)
			(fill no)
			(layer "F.Fab")
		)
		(pad "1" smd rect
			(at 0 0 90)
			(size 1.016 0.381)
			(layers "F.Cu" "F.Mask" "F.Paste")
			(net "GND")
		)
		(pad "2" smd rect
			(at 0 0.65024 90)
			(size 1.016 0.381)
			(layers "F.Cu" "F.Mask" "F.Paste")
			(net "FM_PWR_LED_N")
		)
		(pad "3" smd rect
			(at 0 1.30048 90)
			(size 1.016 0.381)
			(layers "F.Cu" "F.Mask" "F.Paste")
			(net "FM_PWR_LED_K")
		)
		(pad "4" smd rect
			(at 1.778 1.30048 90)
			(size 1.016 0.381)
			(layers "F.Cu" "F.Mask" "F.Paste")
			(net "GND")
		)
		(pad "5" smd rect
			(at 1.778 0.65024 90)
			(size 1.016 0.381)
			(layers "F.Cu" "F.Mask" "F.Paste")
			(net "FM_PWR_LED")
		)
		(pad "6" smd rect
			(at 1.778 0 90)
			(size 1.016 0.381)
			(layers "F.Cu" "F.Mask" "F.Paste")
			(net "FM_PWR_LED")
		)
		(zone
			(layer "F.Cu")
			(hatch none 0.5)
			(connect_pads
				(clearance 0)
			)
			(min_thickness 0.25)
			(keepout
				(tracks allowed)
				(vias not_allowed)
				(pads allowed)
				(copperpour not_allowed)
				(footprints allowed)
			)
			(placement
				(enabled no)
				(sheetname "")
			)
			(fill
				(thermal_gap 0.5)
				(thermal_bridge_width 0.5)
				(island_removal_mode 0)
			)
			(polygon
				(pts
					(xy 475.0308 -139.827) (xy 475.0308 -140.843) (xy 476.7199 -140.843) (xy 476.7199 -139.827)
				)
			)
		)
		(zone
			(layer "F.Cu")
			(hatch none 0.5)
			(connect_pads
				(clearance 0)
			)
			(min_thickness 0.25)
			(keepout
				(tracks allowed)
				(vias not_allowed)
				(pads allowed)
				(copperpour not_allowed)
				(footprints allowed)
			)
			(placement
				(enabled no)
				(sheetname "")
			)
			(fill
				(thermal_gap 0.5)
				(thermal_bridge_width 0.5)
				(island_removal_mode 0)
			)
			(polygon
				(pts
					(xy 475.0308 -138.049) (xy 475.0308 -139.065) (xy 476.7199 -139.065) (xy 476.7199 -138.049)
				)
			)
		)
	)
)
